(kicad_pcb
	(version 20260206)
	(generator "pcbnew")
	(generator_version "10.0")
	(general
		(thickness 1.6)
		(legacy_teardrops no)
	)
	(paper "A4")
	(title_block
		(title "Wiwynn_Tioga_Pass_MB.brd")
		(comment 1 "Tioga Pass / footprint 2988 of 4770 (J6U1), pads 244-291 of 291")
	)
	(layers
		(0 "F.Cu" signal "TOP")
		(4 "In1.Cu" signal "L2GND")
		(6 "In2.Cu" signal "L3")
		(8 "In3.Cu" signal "L4GND")
		(10 "In4.Cu" signal "L5")
		(12 "In5.Cu" signal "L6GND")
		(14 "In6.Cu" signal "L7VCC")
		(16 "In7.Cu" signal "L8VCC")
		(18 "In8.Cu" signal "L9GND")
		(20 "In9.Cu" signal "L10")
		(22 "In10.Cu" signal "L11GND")
		(24 "In11.Cu" signal "L12")
		(26 "In12.Cu" signal "L13GND")
		(2 "B.Cu" signal "BOTTOM")
		(9 "F.Adhes" user "F.Adhesive")
		(11 "B.Adhes" user "B.Adhesive")
		(13 "F.Paste" user "Package Geometry/Pastemask Top")
		(15 "B.Paste" user "Package Geometry/Pastemask Bottom")
		(5 "F.SilkS" user "Ref Des/Silkscreen Top")
		(7 "B.SilkS" user "Ref Des/Silkscreen Bottom")
		(1 "F.Mask" user "Board Geometry/Soldermask Top")
		(3 "B.Mask" user "Board Geometry/Soldermask Bottom")
		(17 "Dwgs.User" user "User.Drawings")
		(19 "Cmts.User" user "User.Comments")
		(21 "Eco1.User" user "User.Eco1")
		(23 "Eco2.User" user "User.Eco2")
		(25 "Edge.Cuts" user "Board Geometry/Outline")
		(27 "Margin" user)
		(31 "F.CrtYd" user "Package Geometry/Place Bound Top")
		(29 "B.CrtYd" user "Package Geometry/Place Bound Bottom")
		(35 "F.Fab" user "Ref Des/Assembly Top")
		(33 "B.Fab" user "Ref Des/Assembly Bottom")
	)
	(footprint ""
		(layer "B.Cu")
		(at 194.700398 -15.222982 90)
		(property "Reference" "J6U1"
			(at 2.530348 39.10711 0)
			(unlocked yes)
			(layer "B.SilkS")
			(effects
				(font
					(size 0.7874 0.5842)
					(thickness 0.1524)
				)
				(justify left mirror)
			)
		)
		(property "Value" ""
			(at 0 0 90)
			(layer "B.Fab")
			(effects
				(font
					(size 1.27 1.27)
				)
				(justify mirror)
			)
		)
		(duplicate_pad_numbers_are_jumpers no)
		(pad "241" smd rect
			(at -4.59994 86.700106 270)
			(size 1.8034 0.508)
			(layers "B.Cu" "B.Mask" "B.Paste")
			(net "GND")
		)
		(pad "242" smd rect
			(at -4.59994 87.54999 270)
			(size 1.8034 0.508)
			(layers "B.Cu" "B.Mask" "B.Paste")
			(net "M_B_DQ<33>")
		)
		(pad "243" smd rect
			(at -4.59994 88.399874 270)
			(size 1.8034 0.508)
			(layers "B.Cu" "B.Mask" "B.Paste")
			(net "GND")
		)
		(pad "244" smd rect
			(at -4.59994 89.250012 270)
			(size 1.8034 0.508)
			(layers "B.Cu" "B.Mask" "B.Paste")
			(net "M_B_DQS_DN<4>")
		)
		(pad "245" smd rect
			(at -4.59994 90.099896 270)
			(size 1.8034 0.508)
			(layers "B.Cu" "B.Mask" "B.Paste")
			(net "M_B_DQS_DP<4>")
		)
		(pad "246" smd rect
			(at -4.59994 90.950034 270)
			(size 1.8034 0.508)
			(layers "B.Cu" "B.Mask" "B.Paste")
			(net "GND")
		)
		(pad "247" smd rect
			(at -4.59994 91.799918 270)
			(size 1.8034 0.508)
			(layers "B.Cu" "B.Mask" "B.Paste")
			(net "M_B_DQ<39>")
		)
		(pad "248" smd rect
			(at -4.59994 92.650056 270)
			(size 1.8034 0.508)
			(layers "B.Cu" "B.Mask" "B.Paste")
			(net "GND")
		)
		(pad "249" smd rect
			(at -4.59994 93.49994 270)
			(size 1.8034 0.508)
			(layers "B.Cu" "B.Mask" "B.Paste")
			(net "M_B_DQ<35>")
		)
		(pad "250" smd rect
			(at -4.59994 94.350078 270)
			(size 1.8034 0.508)
			(layers "B.Cu" "B.Mask" "B.Paste")
			(net "GND")
		)
		(pad "251" smd rect
			(at -4.59994 95.199962 270)
			(size 1.8034 0.508)
			(layers "B.Cu" "B.Mask" "B.Paste")
			(net "M_B_DQ<45>")
		)
		(pad "252" smd rect
			(at -4.59994 96.0501 270)
			(size 1.8034 0.508)
			(layers "B.Cu" "B.Mask" "B.Paste")
			(net "GND")
		)
		(pad "253" smd rect
			(at -4.59994 96.899984 270)
			(size 1.8034 0.508)
			(layers "B.Cu" "B.Mask" "B.Paste")
			(net "M_B_DQ<41>")
		)
		(pad "254" smd rect
			(at -4.59994 97.750122 270)
			(size 1.8034 0.508)
			(layers "B.Cu" "B.Mask" "B.Paste")
			(net "GND")
		)
		(pad "255" smd rect
			(at -4.59994 98.600006 270)
			(size 1.8034 0.508)
			(layers "B.Cu" "B.Mask" "B.Paste")
			(net "M_B_DQS_DN<5>")
		)
		(pad "256" smd rect
			(at -4.59994 99.44989 270)
			(size 1.8034 0.508)
			(layers "B.Cu" "B.Mask" "B.Paste")
			(net "M_B_DQS_DP<5>")
		)
		(pad "257" smd rect
			(at -4.59994 100.300028 270)
			(size 1.8034 0.508)
			(layers "B.Cu" "B.Mask" "B.Paste")
			(net "GND")
		)
		(pad "258" smd rect
			(at -4.59994 101.149912 270)
			(size 1.8034 0.508)
			(layers "B.Cu" "B.Mask" "B.Paste")
			(net "M_B_DQ<47>")
		)
		(pad "259" smd rect
			(at -4.59994 102.00005 270)
			(size 1.8034 0.508)
			(layers "B.Cu" "B.Mask" "B.Paste")
			(net "GND")
		)
		(pad "260" smd rect
			(at -4.59994 102.849934 270)
			(size 1.8034 0.508)
			(layers "B.Cu" "B.Mask" "B.Paste")
			(net "M_B_DQ<43>")
		)
		(pad "261" smd rect
			(at -4.59994 103.700072 270)
			(size 1.8034 0.508)
			(layers "B.Cu" "B.Mask" "B.Paste")
			(net "GND")
		)
		(pad "262" smd rect
			(at -4.59994 104.549956 270)
			(size 1.8034 0.508)
			(layers "B.Cu" "B.Mask" "B.Paste")
			(net "M_B_DQ<53>")
		)
		(pad "263" smd rect
			(at -4.59994 105.400094 270)
			(size 1.8034 0.508)
			(layers "B.Cu" "B.Mask" "B.Paste")
			(net "GND")
		)
		(pad "264" smd rect
			(at -4.59994 106.249978 270)
			(size 1.8034 0.508)
			(layers "B.Cu" "B.Mask" "B.Paste")
			(net "M_B_DQ<49>")
		)
		(pad "265" smd rect
			(at -4.59994 107.100116 270)
			(size 1.8034 0.508)
			(layers "B.Cu" "B.Mask" "B.Paste")
			(net "GND")
		)
		(pad "266" smd rect
			(at -4.59994 107.95 270)
			(size 1.8034 0.508)
			(layers "B.Cu" "B.Mask" "B.Paste")
			(net "M_B_DQS_DN<6>")
		)
		(pad "267" smd rect
			(at -4.59994 108.799884 270)
			(size 1.8034 0.508)
			(layers "B.Cu" "B.Mask" "B.Paste")
			(net "M_B_DQS_DP<6>")
		)
		(pad "268" smd rect
			(at -4.59994 109.650022 270)
			(size 1.8034 0.508)
			(layers "B.Cu" "B.Mask" "B.Paste")
			(net "GND")
		)
		(pad "269" smd rect
			(at -4.59994 110.499906 270)
			(size 1.8034 0.508)
			(layers "B.Cu" "B.Mask" "B.Paste")
			(net "M_B_DQ<55>")
		)
		(pad "270" smd rect
			(at -4.59994 111.350044 270)
			(size 1.8034 0.508)
			(layers "B.Cu" "B.Mask" "B.Paste")
			(net "GND")
		)
		(pad "271" smd rect
			(at -4.59994 112.199928 270)
			(size 1.8034 0.508)
			(layers "B.Cu" "B.Mask" "B.Paste")
			(net "M_B_DQ<51>")
		)
		(pad "272" smd rect
			(at -4.59994 113.050066 270)
			(size 1.8034 0.508)
			(layers "B.Cu" "B.Mask" "B.Paste")
			(net "GND")
		)
		(pad "273" smd rect
			(at -4.59994 113.89995 270)
			(size 1.8034 0.508)
			(layers "B.Cu" "B.Mask" "B.Paste")
			(net "M_B_DQ<61>")
		)
		(pad "274" smd rect
			(at -4.59994 114.750088 270)
			(size 1.8034 0.508)
			(layers "B.Cu" "B.Mask" "B.Paste")
			(net "GND")
		)
		(pad "275" smd rect
			(at -4.59994 115.599972 270)
			(size 1.8034 0.508)
			(layers "B.Cu" "B.Mask" "B.Paste")
			(net "M_B_DQ<57>")
		)
		(pad "276" smd rect
			(at -4.59994 116.45011 270)
			(size 1.8034 0.508)
			(layers "B.Cu" "B.Mask" "B.Paste")
			(net "GND")
		)
		(pad "277" smd rect
			(at -4.59994 117.299994 270)
			(size 1.8034 0.508)
			(layers "B.Cu" "B.Mask" "B.Paste")
			(net "M_B_DQS_DN<7>")
		)
		(pad "278" smd rect
			(at -4.59994 118.149878 270)
			(size 1.8034 0.508)
			(layers "B.Cu" "B.Mask" "B.Paste")
			(net "M_B_DQS_DP<7>")
		)
		(pad "279" smd rect
			(at -4.59994 119.000016 270)
			(size 1.8034 0.508)
			(layers "B.Cu" "B.Mask" "B.Paste")
			(net "GND")
		)
		(pad "280" smd rect
			(at -4.59994 119.8499 270)
			(size 1.8034 0.508)
			(layers "B.Cu" "B.Mask" "B.Paste")
			(net "M_B_DQ<63>")
		)
		(pad "281" smd rect
			(at -4.59994 120.700038 270)
			(size 1.8034 0.508)
			(layers "B.Cu" "B.Mask" "B.Paste")
			(net "GND")
		)
		(pad "282" smd rect
			(at -4.59994 121.549922 270)
			(size 1.8034 0.508)
			(layers "B.Cu" "B.Mask" "B.Paste")
			(net "M_B_DQ<59>")
		)
		(pad "283" smd rect
			(at -4.59994 122.40006 270)
			(size 1.8034 0.508)
			(layers "B.Cu" "B.Mask" "B.Paste")
			(net "GND")
		)
		(pad "284" smd rect
			(at -4.59994 123.249944 270)
			(size 1.8034 0.508)
			(layers "B.Cu" "B.Mask" "B.Paste")
			(net "PVPP_ABC")
		)
		(pad "285" smd rect
			(at -4.59994 124.100082 270)
			(size 1.8034 0.508)
			(layers "B.Cu" "B.Mask" "B.Paste")
			(net "SMB_DDR_ABC_VPP_SDA")
		)
		(pad "286" smd rect
			(at -4.59994 124.949966 270)
			(size 1.8034 0.508)
			(layers "B.Cu" "B.Mask" "B.Paste")
			(net "PVPP_ABC")
		)
		(pad "287" smd rect
			(at -4.59994 125.800104 270)
			(size 1.8034 0.508)
			(layers "B.Cu" "B.Mask" "B.Paste")
			(net "PVPP_ABC")
		)
		(pad "288" smd rect
			(at -4.59994 126.649988 270)
			(size 1.8034 0.508)
			(layers "B.Cu" "B.Mask" "B.Paste")
			(net "PVPP_ABC")
		)
	)
)
